FILE_TYPE = CONNECTIVITY;
{Allegro Design Entry HDL 17.4-2019 S026 (4007227) 1/17/2022}
"PAGE_NUMBER" = 148;
0"NC";
1"GND\g";
2"GND\g";
3"GND\g";
4"P3V3_AUX\g";
5"GND\g";
6"GND\g";
7"P3V3_AUX\g";
8"GND\g";
9"P3V3_AUX\g";
10"GND\g";
11"GND\g";
12"GND\g";
13"GND\g";
14"GND\g";
15"P3V3_AUX\g";
16"P3V3_AUX\g";
17"JTAG_SCM_MUX_R_TCK";
18"TP_JTAG_SCM_SLOT3_R_TCK";
19"JTAG_SCM_MUX_R_TMS";
20"JTAG_SCM_PLD_R_TDI";
21"JTAG_SCM_MUX_R_TDI";
22"TP_JTAG_SCM_SLOT3_R_TDI";
23"JTAG_SCM_PLD_R_TDO";
24"TP_JTAG_SCM_SLOT3_R_TDO";
25"PU_U212_EN_N";
26"U212_EN_N";
27"P3V3_AUX\g";
28"P3V3_AUX\g";
29"GND\g";
30"P3V3_AUX\g";
31"P3V3_AUX\g";
32"GND\g";
33"P3V3_AUX\g";
34"JTAG_SCM_PLD_TCK";
35"JTAG_SCM_MUX_TDI";
36"JTAG_SCM_MUX_TDO";
37"JTAG_SCM_MUX_TMS";
38"PU_U160_EN_N";
39"U160_EN_N";
40"JTAG_SCM_TDO";
41"SCM_JTAG_MUX_S1";
42"JTAG_SCM_MUX_R_TDO";
43"JTAG_SCM_MUX_TDO";
44"JTAG_SCM_MUX_TCK";
45"JTAG_SCM_MUX_TMS";
46"JTAG_SCM_MUX_TDI";
47"SCM_JTAG_MUX_S0_R1";
48"SCM_JTAG_MUX_S0";
49"TP_JTAG_SCM_SLOT3_R_TMS";
50"FW_RECOVERY_R";
51"JTAG_SCM_PLD_TDI";
52"JTAG_SCM_PLD_R_TMS";
53"JTAG_SCM_TMS";
54"JTAG_SCM_TCK";
55"JTAG_SCM_TDI";
56"JTAG_SCM_MUX_TCK";
57"JTAG_SCM_TDO";
58"PD_U212_EN_N";
59"JTAG_SCM_PLD_TMS";
60"JTAG_SCM_TDI";
61"SCM_JTAG_MUX_S0_R2";
62"JTAG_SCM_PLD_TDO";
63"PD_U160_EN_N";
64"JTAG_SCM_TCK";
65"JTAG_SCM_TMS";
66"JTAG_SCM_PLD_R_TCK";
%"Q_RES"
"2","(-2875,6050)","0","pure_quanta","I244";
;
LOCATION"R1734"
$SEC"1"
CDS_SEC"1"
PACK_TYPE"0402LF"
MATERIAL"CHIP"
TOLERANCE"1%"
VALUE"10K"
WATTAGE"1/16W"
CDS_LIB"pure_quanta"
PART_NUMBER"CS31002FB08";
"A"
$PN"1"27;
"B"
$PN"2"54;
%"Q_RES"
"2","(-3125,6050)","0","pure_quanta","I245";
;
LOCATION"R1731"
$SEC"1"
CDS_SEC"1"
WATTAGE"1/16W"
VALUE"10K"
TOLERANCE"1%"
MATERIAL"EMPTY"
PACK_TYPE"0402LF"
CDS_LIB"pure_quanta"
PART_NUMBER"CS31002FB08";
"A"
$PN"1"27;
"B"
$PN"2"53;
%"Q_RES"
"2","(-2875,5550)","0","pure_quanta","I246";
;
LOCATION"R1735"
$SEC"1"
CDS_SEC"1"
MATERIAL"EMPTY"
VALUE"10K"
TOLERANCE"1%"
CDS_LIB"pure_quanta"
WATTAGE"1/16W"
PACK_TYPE"0402LF"
PART_NUMBER"CS31002FB08";
"A"
$PN"1"54;
"B"
$PN"2"1;
%"UNIVERSAL_GND"
"1","(-2875,5325)","0","pure_quanta_power","I247";
;
CDS_LIB"pure_quanta_power"
HDL_POWER"GND";
"A"1;
%"UNIVERSAL_POWER"
"1","(-3525,6400)","0","pure_quanta_power","I248";
;
HDL_POWER"P3V3_AUX"
CDS_LIB"pure_quanta_power";
"A"27;
%"Q_RES"
"2","(-3325,6050)","0","pure_quanta","I249";
;
LOCATION"R1728"
$SEC"1"
CDS_SEC"1"
VALUE"10K"
TOLERANCE"1%"
MATERIAL"EMPTY"
PACK_TYPE"0402LF"
WATTAGE"1/16W"
CDS_LIB"pure_quanta"
PART_NUMBER"CS31002FB08";
"A"
$PN"1"27;
"B"
$PN"2"55;
%"Q_RES"
"2","(-3525,6050)","0","pure_quanta","I250";
;
LOCATION"R1727"
$SEC"1"
CDS_SEC"1"
TOLERANCE"1%"
MATERIAL"EMPTY"
VALUE"10K"
PACK_TYPE"0402LF"
WATTAGE"1/16W"
CDS_LIB"pure_quanta"
PART_NUMBER"CS31002FB08";
"A"
$PN"1"27;
"B"
$PN"2"57;
%"Q_RES"
"2","(-450,6025)","0","pure_quanta","I255";
;
LOCATION"R1747"
$SEC"1"
CDS_SEC"1"
WATTAGE"1/16W"
MATERIAL"CHIP"
TOLERANCE"1%"
VALUE"10K"
PACK_TYPE"0402LF"
CDS_LIB"pure_quanta"
PART_NUMBER"CS31002FB08";
"A"
$PN"1"28;
"B"
$PN"2"56;
%"Q_RES"
"2","(-675,6025)","0","pure_quanta","I256";
;
LOCATION"R1746"
$SEC"1"
CDS_SEC"1"
WATTAGE"1/16W"
MATERIAL"CHIP"
TOLERANCE"1%"
VALUE"10K"
PACK_TYPE"0402LF"
CDS_LIB"pure_quanta"
PART_NUMBER"CS31002FB08";
"A"
$PN"1"28;
"B"
$PN"2"37;
%"Q_RES"
"2","(-875,6025)","0","pure_quanta","I257";
;
LOCATION"R1745"
$SEC"1"
CDS_SEC"1"
TOLERANCE"1%"
VALUE"10K"
CDS_LIB"pure_quanta"
WATTAGE"1/16W"
MATERIAL"CHIP"
PACK_TYPE"0402LF"
PART_NUMBER"CS31002FB08";
"A"
$PN"1"28;
"B"
$PN"2"36;
%"Q_RES"
"2","(-450,5525)","0","pure_quanta","I258";
;
LOCATION"R1748"
$SEC"1"
CDS_SEC"1"
MATERIAL"EMPTY"
TOLERANCE"1%"
VALUE"10K"
CDS_LIB"pure_quanta"
WATTAGE"1/16W"
PACK_TYPE"0402LF"
PART_NUMBER"CS31002FB08";
"A"
$PN"1"56;
"B"
$PN"2"2;
%"UNIVERSAL_GND"
"1","(-450,5300)","0","pure_quanta_power","I259";
;
CDS_LIB"pure_quanta_power"
HDL_POWER"GND";
"A"2;
%"UNIVERSAL_POWER"
"1","(-1075,6375)","0","pure_quanta_power","I260";
;
HDL_POWER"P3V3_AUX"
CDS_LIB"pure_quanta_power";
"A"28;
%"Q_RES"
"2","(-1075,6025)","0","pure_quanta","I261";
;
LOCATION"R1744"
$SEC"1"
CDS_SEC"1"
TOLERANCE"1%"
VALUE"10K"
CDS_LIB"pure_quanta"
WATTAGE"1/16W"
MATERIAL"CHIP"
PACK_TYPE"0402LF"
PART_NUMBER"CS31002FB08";
"A"
$PN"1"28;
"B"
$PN"2"35;
%"74LV4052PW"
"1","(-4875,4050)","0","pure_quanta","I266";
;
LOCATION"U160"
SEC"1"
MATERIAL"IC"
PART_TYPE"SMLF"
VALUE"74LV4052PW"
SEC_TYPE""
CDS_LIB"pure_quanta"
CDS_LMAN_SYM_OUTLINE"-175,325,175,-325"
NEEDS_NO_SIZE"TRUE"
PART_NUMBER"ALLV4052K19";
"VCC"
$PN"16"30;
"1Y2"
$PN"15"66;
"1Y1"
$PN"14"17;
"1Z"
$PN"13"64;
"1Y0"
$PN"12"18;
"1Y3"
$PN"11"66;
"S0"
$PN"10"47;
"S1"
$PN"9"41;
"GND"
$PN"8"29;
"VEE"
$PN"7"29;
"E_N \B"
$PN"6"39;
"2Y1"
$PN"5"19;
"2Y3"
$PN"4"52;
"2Z"
$PN"3"65;
"2Y2"
$PN"2"52;
"2Y0"
$PN"1"49;
%"UNIVERSAL_GND"
"1","(-4475,3525)","0","pure_quanta_power","I267";
;
CDS_LIB"pure_quanta_power"
HDL_POWER"GND";
"A"29;
%"UNIVERSAL_POWER"
"1","(-5350,4875)","0","pure_quanta_power","I292";
;
HDL_POWER"P3V3_AUX"
CDS_LIB"pure_quanta_power";
"A"30;
%"Q_CAP"
"1","(-5475,4575)","0","pure_quanta","I293";
;
LOCATION"C1554"
$SEC"1"
CDS_SEC"1"
PACK_TYPE"C0402"
MATERIAL"X7R"
TOLERANCE"10%"
VALUE"0.1UF"
VOLTAGE"16V"
CDS_LIB"pure_quanta"
PART_NUMBER"CH4103K1B08";
"B"
$PN"2"3;
"A"
$PN"1"30;
%"UNIVERSAL_GND"
"1","(-5475,4375)","0","pure_quanta_power","I294";
;
CDS_LIB"pure_quanta_power"
HDL_POWER"GND";
"A"3;
%"UNIVERSAL_POWER"
"1","(-7700,4375)","0","pure_quanta_power","I295";
;
HDL_POWER"P3V3_AUX"
CDS_LIB"pure_quanta_power";
"A"4;
%"UNIVERSAL_POWER"
"1","(-5350,2925)","0","pure_quanta_power","I298";
;
HDL_POWER"P3V3_AUX"
CDS_LIB"pure_quanta_power";
"A"31;
%"Q_CAP"
"1","(-5475,2625)","0","pure_quanta","I299";
;
LOCATION"C194"
$SEC"1"
CDS_SEC"1"
VALUE"0.1UF"
VOLTAGE"16V"
TOLERANCE"10%"
PACK_TYPE"C0402"
MATERIAL"X7R"
CDS_LIB"pure_quanta"
PART_NUMBER"CH4103K1B08";
"B"
$PN"2"5;
"A"
$PN"1"31;
%"UNIVERSAL_GND"
"1","(-5475,2425)","0","pure_quanta_power","I300";
;
CDS_LIB"pure_quanta_power"
HDL_POWER"GND";
"A"5;
%"UNIVERSAL_GND"
"1","(-4425,1600)","0","pure_quanta_power","I301";
;
CDS_LIB"pure_quanta_power"
HDL_POWER"GND";
"A"32;
%"74LV4052PW"
"1","(-4825,2100)","0","pure_quanta","I302";
;
LOCATION"U212"
SEC"1"
VALUE"74LV4052PW"
MATERIAL"IC"
PART_TYPE"SMLF"
SEC_TYPE""
CDS_LIB"pure_quanta"
CDS_LMAN_SYM_OUTLINE"-175,325,175,-325"
NEEDS_NO_SIZE"TRUE"
PART_NUMBER"ALLV4052K19";
"VCC"
$PN"16"31;
"1Y2"
$PN"15"20;
"1Y1"
$PN"14"21;
"1Z"
$PN"13"60;
"1Y0"
$PN"12"22;
"1Y3"
$PN"11"20;
"S0"
$PN"10"61;
"S1"
$PN"9"41;
"GND"
$PN"8"32;
"VEE"
$PN"7"32;
"E_N \B"
$PN"6"26;
"2Y1"
$PN"5"42;
"2Y3"
$PN"4"23;
"2Z"
$PN"3"40;
"2Y2"
$PN"2"23;
"2Y0"
$PN"1"24;
%"Q_RES"
"2","(-7700,4150)","0","pure_quanta","I305";
;
LOCATION"R1730"
$SEC"1"
CDS_SEC"1"
PACK_TYPE"0402LF"
MATERIAL"EMPTY"
VALUE"4.7K"
TOLERANCE"5%"
WATTAGE"1/16W"
CDS_LIB"pure_quanta"
PART_NUMBER"CS24702JB10";
"A"
$PN"1"4;
"B"
$PN"2"41;
%"Q_RES"
"2","(-7750,3650)","0","pure_quanta","I306";
;
LOCATION"R1729"
$SEC"1"
CDS_SEC"1"
PACK_TYPE"0402LF"
WATTAGE"1/16W"
TOLERANCE"5%"
MATERIAL"CHIP"
VALUE"4.7K"
CDS_LIB"pure_quanta"
PART_NUMBER"CS24702JB10";
"A"
$PN"1"41;
"B"
$PN"2"6;
%"UNIVERSAL_GND"
"1","(-7750,3400)","0","pure_quanta_power","I307";
;
CDS_LIB"pure_quanta_power"
HDL_POWER"GND";
"A"6;
%"UNIVERSAL_POWER"
"1","(-7700,2375)","0","pure_quanta_power","I308";
;
HDL_POWER"P3V3_AUX"
CDS_LIB"pure_quanta_power";
"A"7;
%"Q_RES"
"2","(-7700,2150)","0","pure_quanta","I309";
;
LOCATION"R1659"
$SEC"1"
CDS_SEC"1"
VALUE"4.7K"
TOLERANCE"5%"
MATERIAL"EMPTY"
WATTAGE"1/16W"
PACK_TYPE"0402LF"
CDS_LIB"pure_quanta"
PART_NUMBER"CS24702JB10";
"A"
$PN"1"7;
"B"
$PN"2"48;
%"Q_RES"
"2","(-7750,1650)","0","pure_quanta","I310";
;
LOCATION"R1658"
$SEC"1"
CDS_SEC"1"
WATTAGE"1/16W"
PACK_TYPE"0402LF"
VALUE"4.7K"
TOLERANCE"5%"
MATERIAL"CHIP"
CDS_LIB"pure_quanta"
PART_NUMBER"CS24702JB10";
"A"
$PN"1"48;
"B"
$PN"2"8;
%"UNIVERSAL_GND"
"1","(-7750,1400)","0","pure_quanta_power","I311";
;
CDS_LIB"pure_quanta_power"
HDL_POWER"GND";
"A"8;
%"Q_RES"
"1","(-3200,2075)","0","pure_quanta","I332";
;
LOCATION"R1743"
$SEC"1"
CDS_SEC"1"
TOLERANCE"1%"
VALUE"22"
MATERIAL"CHIP"
PACK_TYPE"0402LF"
WATTAGE"1/16W"
CDS_LIB"pure_quanta"
PART_NUMBER"CS02202FB02";
"B"
$PN"2"62;
"A"
$PN"1"23;
%"UNIVERSAL_POWER"
"1","(-6575,5775)","0","pure_quanta_power","I337";
;
HDL_POWER"P3V3_AUX"
CDS_LIB"pure_quanta_power"
BOM_COST"OCP3.0 ";
"A"9;
%"Q_RES"
"2","(-6575,5500)","0","pure_quanta","I339";
;
LOCATION"R1343"
$SEC"1"
CDS_SEC"1"
WATTAGE"1/16W"
PACK_TYPE"0402LF"
VALUE"4.7K"
TOLERANCE"5%"
MATERIAL"EMPTY"
CDS_LIB"pure_quanta"
BOM_COST"OCP3.0 "
PART_NUMBER"CS24702JB10";
"A"
$PN"1"9;
"B"
$PN"2"41;
%"SN74LVC1G07DBVR"
"1","(-7400,5225)","0","pure_quanta","I340";
;
LOCATION"U99"
$SEC"1"
CDS_SEC"1"
MATERIAL"EMPTY"
VALUE"SN74LVC1G07DBVR"
PACK_TYPE"SMLF"
NEEDS_NO_SIZE"TRUE"
CDS_LIB"pure_quanta"
PART_NUMBER"AL1G0007024";
"NC"
$PN"1"0;
"Y"
$PN"4"41;
"GND"
$PN"3"11;
"A"
$PN"2"50;
"VCC"
$PN"5"33;
%"UNIVERSAL_POWER"
"1","(-8000,5850)","0","pure_quanta_power","I341";
;
HDL_POWER"P3V3_AUX"
CDS_LIB"pure_quanta_power"
BOM_COST"OCP3.0 ";
"A"33;
%"Q_CAP"
"1","(-8000,5550)","0","pure_quanta","I342";
;
LOCATION"C553"
$SEC"1"
CDS_SEC"1"
TOLERANCE"10%"
VALUE"0.1UF"
VOLTAGE"25V"
PACK_TYPE"0402"
MATERIAL"X7R"
BOM_COST"OCP3.0 "
CDS_LIB"pure_quanta"
PART_NUMBER"CH4104K1B00";
"B"
$PN"2"10;
"A"
$PN"1"33;
%"UNIVERSAL_GND"
"1","(-8000,5350)","0","pure_quanta_power","I343";
;
CDS_LIB"pure_quanta_power"
BOM_COST"OCP3.0 "
HDL_POWER"GND";
"A"10;
%"UNIVERSAL_GND"
"1","(-7650,4950)","0","pure_quanta_power","I344";
;
CDS_LIB"pure_quanta_power"
HDL_POWER"GND";
"A"11;
%"Q_RES"
"1","(-3200,2275)","0","pure_quanta","I349";
;
LOCATION"R1738"
$SEC"1"
CDS_SEC"1"
MATERIAL"CHIP"
VALUE"0"
TOLERANCE"5%"
PACK_TYPE"0402LF"
WATTAGE"1/16W"
CDS_LIB"pure_quanta"
PART_NUMBER"CS00002JB13";
"B"
$PN"2"46;
"A"
$PN"1"21;
%"Q_RES"
"1","(-3200,2325)","0","pure_quanta","I352";
;
LOCATION"R1742"
$SEC"1"
CDS_SEC"1"
TOLERANCE"1%"
VALUE"22"
MATERIAL"CHIP"
PACK_TYPE"0402LF"
WATTAGE"1/16W"
CDS_LIB"pure_quanta"
PART_NUMBER"CS02202FB02";
"B"
$PN"2"51;
"A"
$PN"1"20;
%"Q_RES"
"1","(-3200,3975)","0","pure_quanta","I357";
;
LOCATION"R1737"
$SEC"1"
CDS_SEC"1"
TOLERANCE"5%"
VALUE"0"
MATERIAL"CHIP"
CDS_LIB"pure_quanta"
WATTAGE"1/16W"
PACK_TYPE"0402LF"
PART_NUMBER"CS00002JB13";
"B"
$PN"2"45;
"A"
$PN"1"19;
%"Q_RES"
"1","(-3200,4225)","0","pure_quanta","I363";
;
LOCATION"R1736"
$SEC"1"
CDS_SEC"1"
TOLERANCE"5%"
VALUE"0"
MATERIAL"CHIP"
CDS_LIB"pure_quanta"
WATTAGE"1/16W"
PACK_TYPE"0402LF"
PART_NUMBER"CS00002JB13";
"B"
$PN"2"44;
"A"
$PN"1"17;
%"Q_RES"
"1","(-3200,4025)","0","pure_quanta","I366";
;
LOCATION"R1741"
$SEC"1"
CDS_SEC"1"
MATERIAL"CHIP"
VALUE"22"
TOLERANCE"1%"
PACK_TYPE"0402LF"
WATTAGE"1/16W"
CDS_LIB"pure_quanta"
PART_NUMBER"CS02202FB02";
"B"
$PN"2"59;
"A"
$PN"1"52;
%"Q_RES"
"1","(-3200,4275)","0","pure_quanta","I368";
;
LOCATION"R1740"
$SEC"1"
CDS_SEC"1"
MATERIAL"CHIP"
VALUE"22"
TOLERANCE"1%"
PACK_TYPE"0402LF"
WATTAGE"1/16W"
CDS_LIB"pure_quanta"
PART_NUMBER"CS02202FB02";
"B"
$PN"2"34;
"A"
$PN"1"66;
%"Q_RES"
"2","(-8025,5025)","0","pure_quanta","I369";
;
LOCATION"R1342"
$SEC"1"
CDS_SEC"1"
WATTAGE"1/16W"
MATERIAL"CHIP"
TOLERANCE"1%"
VALUE"10K"
PACK_TYPE"0402LF"
CDS_LIB"pure_quanta"
PART_NUMBER"CS31002FB08";
"A"
$PN"1"50;
"B"
$PN"2"12;
%"UNIVERSAL_GND"
"1","(-8025,4750)","0","pure_quanta_power","I370";
;
CDS_LIB"pure_quanta_power"
HDL_POWER"GND";
"A"12;
%"UNIVERSAL_GND"
"1","(-4225,2675)","0","pure_quanta_power","I372";
;
CDS_LIB"pure_quanta_power"
HDL_POWER"GND";
"A"13;
%"Q_RES"
"1","(-6125,3875)","0","pure_quanta","I375";
;
LOCATION"R6101"
$SEC"1"
CDS_SEC"1"
VALUE"0"
CDS_LIB"pure_quanta"
BOM_COST"MEM"
WATTAGE"1/16W"
MATERIAL"CHIP"
PACK_TYPE"0402LF"
TOLERANCE"5%"
PART_NUMBER"CS00002JB13";
"B"
$PN"2"47;
"A"
$PN"1"48;
%"Q_RES"
"1","(-6175,1925)","0","pure_quanta","I376";
;
LOCATION"R6102"
$SEC"1"
CDS_SEC"1"
VALUE"0"
PACK_TYPE"0402LF"
TOLERANCE"5%"
MATERIAL"CHIP"
WATTAGE"1/16W"
BOM_COST"MEM"
CDS_LIB"pure_quanta"
PART_NUMBER"CS00002JB13";
"B"
$PN"2"61;
"A"
$PN"1"48;
%"Q_RES"
"2","(-5400,1000)","0","pure_quanta","I378";
;
LOCATION"R1318"
$SEC"1"
CDS_SEC"1"
WATTAGE"1/16W"
VALUE"4.7K"
MATERIAL"CHIP"
PACK_TYPE"0402LF"
TOLERANCE"5%"
CDS_LIB"pure_quanta"
PART_NUMBER"CS24702JB10";
"A"
$PN"1"58;
"B"
$PN"2"14;
%"UNIVERSAL_GND"
"1","(-5400,700)","0","pure_quanta_power","I379";
;
CDS_LIB"pure_quanta_power"
HDL_POWER"GND";
"A"14;
%"UNIVERSAL_POWER"
"1","(-5400,1750)","0","pure_quanta_power","I380";
;
HDL_POWER"P3V3_AUX"
CDS_LIB"pure_quanta_power";
"A"15;
%"Q_RES"
"2","(-5400,1550)","0","pure_quanta","I381";
;
LOCATION"R6181"
$SEC"1"
CDS_SEC"1"
WATTAGE"1/16W"
TOLERANCE"5%"
PACK_TYPE"0402LF"
VALUE"4.7K"
MATERIAL"CHIP"
CDS_LIB"pure_quanta"
PART_NUMBER"CS24702JB10";
"A"
$PN"1"15;
"B"
$PN"2"25;
%"Q_RES"
"2","(-4225,2900)","0","pure_quanta","I383";
;
LOCATION"R1313"
$SEC"1"
CDS_SEC"1"
PACK_TYPE"0402LF"
WATTAGE"1/16W"
TOLERANCE"5%"
VALUE"4.7K"
MATERIAL"CHIP"
CDS_LIB"pure_quanta"
PART_NUMBER"CS24702JB10";
"A"
$PN"1"63;
"B"
$PN"2"13;
%"Q_RES"
"2","(-4250,3575)","0","pure_quanta","I384";
;
LOCATION"R6182"
$SEC"1"
CDS_SEC"1"
WATTAGE"1/16W"
PACK_TYPE"0402LF"
MATERIAL"CHIP"
TOLERANCE"5%"
VALUE"4.7K"
CDS_LIB"pure_quanta"
PART_NUMBER"CS24702JB10";
"A"
$PN"1"16;
"B"
$PN"2"38;
%"UNIVERSAL_POWER"
"1","(-4250,3800)","0","pure_quanta_power","I385";
;
HDL_POWER"P3V3_AUX"
CDS_LIB"pure_quanta_power";
"A"16;
%"CONN3_210HP1030BR1"
"1","(-4700,1200)","0","pure_quanta","I386";
;
LOCATION"JP6000"
SEC"1"
PART_TYPE"THLF"
VALUE"CONN3_210-HP1-030BR1"
MATERIAL"IO"
NEEDS_NO_SIZE"TRUE"
SEC_TYPE""
CDS_LMAN_SYM_OUTLINE"-50,100,50,-100"
CDS_LIB"pure_quanta"
PART_NUMBER"DFHD03MS213";
"1"
$PN"1"25;
"2"
$PN"2"26;
"3"
$PN"3"58;
%"CONN3_210HP1030BR1"
"1","(-3650,3150)","0","pure_quanta","I387";
;
LOCATION"JP6001"
$SEC"1"
CDS_SEC"1"
VALUE"CONN3_210-HP1-030BR1"
MATERIAL"IO"
PART_TYPE"THLF"
CDS_LIB"pure_quanta"
CDS_LMAN_SYM_OUTLINE"-50,100,50,-100"
NEEDS_NO_SIZE"TRUE"
PART_NUMBER"DFHD03MS213";
"1"
$PN"1"38;
"2"
$PN"2"39;
"3"
$PN"3"63;
%"Q_RES"
"1","(-3200,2025)","0","pure_quanta","I388";
;
LOCATION"R1739"
$SEC"1"
CDS_SEC"1"
MATERIAL"CHIP"
VALUE"0"
TOLERANCE"5%"
CDS_LIB"pure_quanta"
PACK_TYPE"0402LF"
WATTAGE"1/16W"
PART_NUMBER"CS00002JB13";
"B"
$PN"2"43;
"A"
$PN"1"42;
END.
